FILE_TYPE = CONNECTIVITY;
{Allegro Design Entry HDL 17.2-2016 S081 (4005846) 1/11/2022}
"PAGE_NUMBER" = 181;
0"NC";
1"P1V05_PCH_PLL_AUX\g";
2"P1V05_PCH_AUX\g";
3"P1V05_PCH_PLL_AUX\g";
4"P3V3_AUX\g";
5"P1V8_PCH_PLL_AUX\g";
6"P1V05_PCH_PLL_AUX\g";
7"P1V05_PCH_AUX\g";
8"P1V8_PCH_PLL_AUX\g";
9"P1V8_PCH_AUX\g";
10"P1V8_PCH_PLL_AUX\g";
11"P1V05_PCH_AUX\g";
12"P1V05_PCH_AUX\g";
13"P1V8_PCH_AUX\g";
14"P1V8_PCH_AUX\g";
15"P1V05_PCH_AUX\g";
16"P1V05_PCH_AUX\g";
17"P3V3_AUX\g";
18"P1V05_PCH_AUX\g";
19"P1V05_PCH_AUX\g";
20"P3V3_AUX\g";
21"P1V8_PCH_PLL_AUX\g";
22"P1V05_PCH_PLL_AUX\g";
23"GND\g";
24"GND\g";
25"GND\g";
26"GND\g";
27"GND\g";
28"GND\g";
29"GND\g";
30"GND\g";
31"GND\g";
32"GND\g";
33"GND\g";
34"GND\g";
35"GND\g";
36"GND\g";
37"GND\g";
38"GND\g";
39"GND\g";
40"GND\g";
41"GND\g";
42"GND\g";
43"GND\g";
44"GND\g";
%"UNIVERSAL_POWER"
"1","(3800,2925)","0","logical_power","I103";
;
HDL_POWER"P1V05_PCH_PLL_AUX"
CDS_LIB"logical_power";
"A"3;
%"Q_CAP"
"1","(3800,2650)","0","pure_quanta","I104";
;
PART_NUMBER"CH6101MEB01"
VALUE"10UF"
VOLTAGE"6.3V"
MATERIAL"X6S"
PACK_TYPE"C0402"
TOLERANCE"20%"
$LOCATION"C1262"
CDS_LIB"pure_quanta"
CDS_LOCATION"C1262"
$SEC"1"
CDS_SEC"1";
"B"
$PN"2"24;
"A"
$PN"1"3;
%"UNIVERSAL_GND"
"1","(3275,2300)","0","logical_power","I106";
;
ROOM"IO_SLOT"
HDL_POWER"GND"
CDS_LIB"logical_power";
"A"23;
%"UNIVERSAL_POWER"
"1","(2375,2925)","0","logical_power","I108";
;
HDL_POWER"P1V05_PCH_PLL_AUX"
CDS_LIB"logical_power";
"A"6;
%"UNIVERSAL_POWER"
"1","(-850,4100)","0","logical_power","I11";
;
HDL_POWER"P1V05_PCH_AUX"
CDS_LIB"logical_power";
"A"7;
%"Q_CAP"
"1","(2375,2650)","0","pure_quanta","I110";
;
PART_NUMBER"CH6101ME900"
MATERIAL"X6S"
VOLTAGE"6.3V"
TOLERANCE"20%"
VALUE"10UF"
PACK_TYPE"C0603"
$LOCATION"C1251"
CDS_LIB"pure_quanta"
CDS_LOCATION"C1251"
$SEC"1"
CDS_SEC"1";
"B"
$PN"2"23;
"A"
$PN"1"6;
%"Q_CAP"
"1","(2825,2650)","0","pure_quanta","I111";
;
PART_NUMBER"CH6101ME900"
VOLTAGE"6.3V"
TOLERANCE"20%"
VALUE"10UF"
MATERIAL"X6S"
PACK_TYPE"C0603"
$LOCATION"C1254"
CDS_LIB"pure_quanta"
CDS_LOCATION"C1254"
$SEC"1"
CDS_SEC"1";
"B"
$PN"2"23;
"A"
$PN"1"6;
%"UNIVERSAL_GND"
"1","(3800,2300)","0","logical_power","I113";
;
ROOM"IO_SLOT"
HDL_POWER"GND"
CDS_LIB"logical_power";
"A"24;
%"UNIVERSAL_GND"
"1","(4700,2300)","0","logical_power","I114";
;
ROOM"IO_SLOT"
HDL_POWER"GND"
CDS_LIB"logical_power";
"A"25;
%"UNIVERSAL_POWER"
"1","(4700,275)","0","logical_power","I115";
;
HDL_POWER"P1V8_PCH_PLL_AUX"
CDS_LIB"logical_power";
"A"5;
%"UNIVERSAL_GND"
"1","(4700,-350)","0","logical_power","I117";
;
ROOM"IO_SLOT"
HDL_POWER"GND"
CDS_LIB"logical_power";
"A"26;
%"UNIVERSAL_POWER"
"1","(3800,275)","0","logical_power","I118";
;
HDL_POWER"P1V8_PCH_PLL_AUX"
CDS_LIB"logical_power";
"A"8;
%"Q_CAP"
"1","(3800,0)","0","pure_quanta","I119";
;
PART_NUMBER"CH6101MEB01"
PACK_TYPE"C0402"
MATERIAL"X6S"
TOLERANCE"20%"
VOLTAGE"6.3V"
VALUE"10UF"
$LOCATION"C1263"
CDS_LIB"pure_quanta"
CDS_LOCATION"C1263"
$SEC"1"
CDS_SEC"1";
"B"
$PN"2"28;
"A"
$PN"1"8;
%"Q_CAP"
"1","(-850,3825)","0","pure_quanta","I12";
;
PART_NUMBER"CH6101MEB01"
PACK_TYPE"C0402"
MATERIAL"X6S"
TOLERANCE"20%"
VOLTAGE"6.3V"
VALUE"10UF"
$LOCATION"C1205"
CDS_LIB"pure_quanta"
CDS_LOCATION"C1205"
$SEC"1"
CDS_SEC"1";
"B"
$PN"2"31;
"A"
$PN"1"7;
%"UNIVERSAL_GND"
"1","(3300,-350)","0","logical_power","I122";
;
ROOM"IO_SLOT"
HDL_POWER"GND"
CDS_LIB"logical_power";
"A"27;
%"Q_CAP"
"1","(2850,0)","0","pure_quanta","I123";
;
PART_NUMBER"CH6101ME900"
VALUE"10UF"
MATERIAL"X6S"
VOLTAGE"6.3V"
TOLERANCE"20%"
PACK_TYPE"C0603"
$LOCATION"C1255"
CDS_LIB"pure_quanta"
CDS_LOCATION"C1255"
$SEC"1"
CDS_SEC"1";
"B"
$PN"2"27;
"A"
$PN"1"21;
%"UNIVERSAL_POWER"
"1","(2400,275)","0","logical_power","I124";
;
HDL_POWER"P1V8_PCH_PLL_AUX"
CDS_LIB"logical_power";
"A"21;
%"Q_CAP"
"1","(2400,0)","0","pure_quanta","I125";
;
PART_NUMBER"CH6101ME900"
VOLTAGE"6.3V"
MATERIAL"X6S"
TOLERANCE"20%"
PACK_TYPE"C0603"
VALUE"10UF"
$LOCATION"C1252"
CDS_LIB"pure_quanta"
CDS_LOCATION"C1252"
$SEC"1"
CDS_SEC"1";
"B"
$PN"2"27;
"A"
$PN"1"21;
%"UNIVERSAL_GND"
"1","(4250,-350)","0","logical_power","I126";
;
ROOM"IO_SLOT"
HDL_POWER"GND"
CDS_LIB"logical_power";
"A"28;
%"Q_CAP"
"1","(4250,0)","0","pure_quanta","I127";
;
PART_NUMBER"CH6101MEB01"
VALUE"10UF"
TOLERANCE"20%"
MATERIAL"X6S"
PACK_TYPE"C0402"
VOLTAGE"6.3V"
$LOCATION"C1266"
CDS_LIB"pure_quanta"
CDS_LOCATION"C1266"
$SEC"1"
CDS_SEC"1";
"B"
$PN"2"28;
"A"
$PN"1"8;
%"UNIVERSAL_POWER"
"1","(2375,4375)","0","logical_power","I128";
;
HDL_POWER"P1V05_PCH_AUX"
CDS_LIB"logical_power";
"A"2;
%"Q_RES"
"1","(3150,3950)","0","pure_quanta","I129";
;
PART_NUMBER"CS00002JB13"
TOLERANCE"5%"
VALUE"0"
MATERIAL"CHIP"
WATTAGE"1/16W"
PACK_TYPE"0402LF"
$LOCATION"R1463"
CDS_LIB"pure_quanta"
CDS_LOCATION"R1463"
$SEC"1"
CDS_SEC"1";
"B"
$PN"2"1;
"A"
$PN"1"2;
%"Q_CAP"
"1","(-400,3825)","0","pure_quanta","I13";
;
PART_NUMBER"CH6101MEB01"
VALUE"10UF"
MATERIAL"X6S"
PACK_TYPE"C0402"
TOLERANCE"20%"
VOLTAGE"6.3V"
$LOCATION"C1228"
CDS_LIB"pure_quanta"
CDS_LOCATION"C1228"
$SEC"1"
CDS_SEC"1";
"B"
$PN"2"31;
"A"
$PN"1"7;
%"UNIVERSAL_POWER"
"1","(3950,4350)","0","logical_power","I130";
;
HDL_POWER"P1V05_PCH_PLL_AUX"
CDS_LIB"logical_power";
"A"1;
%"Q_CAP"
"1","(3550,3575)","0","pure_quanta","I131";
;
PART_NUMBER"CH6101ME900"
PACK_TYPE"C0603"
MATERIAL"X6S"
TOLERANCE"20%"
VOLTAGE"6.3V"
VALUE"10UF"
$LOCATION"C1260"
CDS_LIB"pure_quanta"
CDS_LOCATION"C1260"
$SEC"1"
CDS_SEC"1";
"B"
$PN"2"30;
"A"
$PN"1"1;
%"UNIVERSAL_GND"
"1","(2375,3225)","0","logical_power","I132";
;
ROOM"IO_SLOT"
HDL_POWER"GND"
CDS_LIB"logical_power";
"A"29;
%"Q_CAP"
"1","(3950,3575)","0","pure_quanta","I133";
;
PART_NUMBER"CH5101K1B01"
TOLERANCE"10%"
VOLTAGE"6.3V"
MATERIAL"EMPTY"
VALUE"1UF"
PACK_TYPE"0402"
$LOCATION"C1264"
CDS_LIB"pure_quanta"
CDS_LOCATION"C1264"
$SEC"1"
CDS_SEC"1";
"B"
$PN"2"30;
"A"
$PN"1"1;
%"UNIVERSAL_GND"
"1","(3950,3225)","0","logical_power","I134";
;
ROOM"IO_SLOT"
HDL_POWER"GND"
CDS_LIB"logical_power";
"A"30;
%"Q_CAP"
"1","(3025,3575)","0","pure_quanta","I136";
;
PART_NUMBER"CH5101K1B01"
VALUE"1UF"
PACK_TYPE"0402"
MATERIAL"EMPTY"
TOLERANCE"10%"
VOLTAGE"6.3V"
$LOCATION"C1256"
CDS_LIB"pure_quanta"
CDS_LOCATION"C1256"
$SEC"1"
CDS_SEC"1";
"B"
$PN"2"29;
"A"
$PN"1"1;
%"Q_CAP"
"1","(2375,3575)","0","pure_quanta","I137";
;
PART_NUMBER"CH5101K1B01"
VALUE"1UF"
PACK_TYPE"0402"
TOLERANCE"10%"
VOLTAGE"6.3V"
MATERIAL"EMPTY"
$LOCATION"C1250"
CDS_LIB"pure_quanta"
CDS_LOCATION"C1250"
$SEC"1"
CDS_SEC"1";
"B"
$PN"2"29;
"A"
$PN"1"2;
%"UNIVERSAL_POWER"
"1","(2425,1425)","0","logical_power","I138";
;
HDL_POWER"P1V8_PCH_AUX"
CDS_LIB"logical_power";
"A"9;
%"UNIVERSAL_POWER"
"1","(4000,1400)","0","logical_power","I139";
;
HDL_POWER"P1V8_PCH_PLL_AUX"
CDS_LIB"logical_power";
"A"10;
%"UNIVERSAL_GND"
"1","(-400,3475)","0","logical_power","I14";
;
ROOM"IO_SLOT"
HDL_POWER"GND"
CDS_LIB"logical_power";
"A"31;
%"Q_CAP"
"1","(4000,900)","0","pure_quanta","I140";
;
PART_NUMBER"CH5101K1B01"
MATERIAL"EMPTY"
PACK_TYPE"0402"
VOLTAGE"6.3V"
VALUE"1UF"
TOLERANCE"10%"
$LOCATION"C1265"
CDS_LIB"pure_quanta"
CDS_LOCATION"C1265"
$SEC"1"
CDS_SEC"1";
"B"
$PN"2"32;
"A"
$PN"1"10;
%"UNIVERSAL_GND"
"1","(4000,550)","0","logical_power","I141";
;
ROOM"IO_SLOT"
HDL_POWER"GND"
CDS_LIB"logical_power";
"A"32;
%"Q_CAP"
"1","(3600,900)","0","pure_quanta","I142";
;
PART_NUMBER"CH6101ME900"
PACK_TYPE"C0603"
VALUE"10UF"
VOLTAGE"6.3V"
TOLERANCE"20%"
MATERIAL"X6S"
$LOCATION"C1261"
CDS_LIB"pure_quanta"
CDS_LOCATION"C1261"
$SEC"1"
CDS_SEC"1";
"B"
$PN"2"32;
"A"
$PN"1"10;
%"UNIVERSAL_GND"
"1","(2425,500)","0","logical_power","I143";
;
ROOM"IO_SLOT"
HDL_POWER"GND"
CDS_LIB"logical_power";
"A"33;
%"Q_RES"
"1","(3200,1275)","0","pure_quanta","I144";
;
PART_NUMBER"CS00002JB13"
PACK_TYPE"0402LF"
WATTAGE"1/16W"
MATERIAL"CHIP"
TOLERANCE"5%"
VALUE"0"
$LOCATION"R1464"
CDS_LIB"pure_quanta"
CDS_LOCATION"R1464"
$SEC"1"
CDS_SEC"1";
"B"
$PN"2"10;
"A"
$PN"1"9;
%"Q_INDUCTOR"
"1","(2750,1100)","0","pure_quanta","I145";
;
PART_NUMBER"CX8PG121009"
VALUE"BLM18PG121SN1D/2000MA"
MATERIAL"EMPTY"
PACK_TYPE"SMLF"
$LOCATION"L10"
NEEDS_NO_SIZE"TRUE"
CDS_LIB"pure_quanta"
CDS_LOCATION"L10"
$SEC"1"
CDS_SEC"1";
"1"
$PN"1"9;
"2"
$PN"2"10;
%"Q_CAP"
"1","(3075,900)","0","pure_quanta","I146";
;
PART_NUMBER"CH5101K1B01"
MATERIAL"EMPTY"
PACK_TYPE"0402"
VOLTAGE"6.3V"
VALUE"1UF"
TOLERANCE"10%"
$LOCATION"C1257"
CDS_LIB"pure_quanta"
CDS_LOCATION"C1257"
$SEC"1"
CDS_SEC"1";
"B"
$PN"2"33;
"A"
$PN"1"10;
%"Q_CAP"
"1","(2425,900)","0","pure_quanta","I147";
;
PART_NUMBER"CH5101K1B01"
PACK_TYPE"0402"
VALUE"1UF"
VOLTAGE"6.3V"
TOLERANCE"10%"
MATERIAL"EMPTY"
$LOCATION"C1253"
CDS_LIB"pure_quanta"
CDS_LOCATION"C1253"
$SEC"1"
CDS_SEC"1";
"B"
$PN"2"33;
"A"
$PN"1"9;
%"UNIVERSAL_POWER"
"1","(-900,1475)","0","logical_power","I148";
;
HDL_POWER"P1V05_PCH_AUX"
CDS_LIB"logical_power";
"A"11;
%"UNIVERSAL_POWER"
"1","(500,1450)","0","logical_power","I149";
;
HDL_POWER"P1V05_PCH_AUX"
CDS_LIB"logical_power";
"A"19;
%"UNIVERSAL_POWER"
"1","(-2250,750)","0","logical_power","I150";
;
HDL_POWER"P1V05_PCH_AUX"
CDS_LIB"logical_power";
"A"12;
%"Q_CAP"
"1","(4700,0)","0","pure_quanta","I151";
;
PART_NUMBER"CH647KMEA04"
VOLTAGE"4V"
MATERIAL"X6S"
VALUE"47UF"
PACK_TYPE"C0805"
TOLERANCE"20%"
LOCATION"C1273"
CDS_LIB"pure_quanta"
$SEC"1"
CDS_SEC"1";
"B"
$PN"2"26;
"A"
$PN"1"5;
%"Q_CAP"
"1","(50,3825)","0","pure_quanta","I152";
;
PART_NUMBER"CH647KMEA04"
TOLERANCE"20%"
MATERIAL"X6S"
VALUE"47UF"
VOLTAGE"4V"
PACK_TYPE"C0805"
LOCATION"C1244"
CDS_LIB"pure_quanta"
$SEC"1"
CDS_SEC"1";
"B"
$PN"2"34;
"A"
$PN"1"18;
%"Q_CAP"
"1","(500,3825)","0","pure_quanta","I153";
;
PART_NUMBER"CH647KMEA04"
MATERIAL"X6S"
TOLERANCE"20%"
VALUE"47UF"
VOLTAGE"4V"
PACK_TYPE"C0805"
LOCATION"C1246"
CDS_LIB"pure_quanta"
$SEC"1"
CDS_SEC"1";
"B"
$PN"2"34;
"A"
$PN"1"18;
%"Q_CAP"
"1","(500,1175)","0","pure_quanta","I154";
;
PART_NUMBER"CH647KMEA04"
MATERIAL"X6S"
VOLTAGE"4V"
TOLERANCE"20%"
VALUE"47UF"
PACK_TYPE"C0805"
LOCATION"C1247"
CDS_LIB"pure_quanta"
$SEC"1"
CDS_SEC"1";
"B"
$PN"2"41;
"A"
$PN"1"19;
%"Q_CAP"
"1","(950,3825)","0","pure_quanta","I155";
;
PART_NUMBER"CH647KMEA04"
PACK_TYPE"C0805"
VALUE"47UF"
VOLTAGE"4V"
MATERIAL"X6S"
TOLERANCE"20%"
LOCATION"C1248"
CDS_LIB"pure_quanta"
$SEC"1"
CDS_SEC"1";
"B"
$PN"2"34;
"A"
$PN"1"18;
%"Q_CAP"
"1","(950,1175)","0","pure_quanta","I156";
;
PART_NUMBER"CH647KMEA04"
MATERIAL"X6S"
VALUE"47UF"
PACK_TYPE"C0805"
VOLTAGE"4V"
TOLERANCE"20%"
LOCATION"C1249"
CDS_LIB"pure_quanta"
$SEC"1"
CDS_SEC"1";
"B"
$PN"2"41;
"A"
$PN"1"19;
%"Q_CAP"
"1","(3275,2650)","0","pure_quanta","I157";
;
PART_NUMBER"CH647KMEA04"
VALUE"47UF"
PACK_TYPE"C0805"
VOLTAGE"4V"
TOLERANCE"20%"
MATERIAL"X6S"
LOCATION"C1258"
CDS_LIB"pure_quanta"
$SEC"1"
CDS_SEC"1";
"B"
$PN"2"23;
"A"
$PN"1"6;
%"Q_CAP"
"1","(3300,0)","0","pure_quanta","I158";
;
PART_NUMBER"CH647KMEA04"
MATERIAL"X6S"
VALUE"47UF"
PACK_TYPE"C0805"
VOLTAGE"4V"
TOLERANCE"20%"
LOCATION"C1259"
CDS_LIB"pure_quanta"
$SEC"1"
CDS_SEC"1";
"B"
$PN"2"27;
"A"
$PN"1"21;
%"Q_CAP"
"1","(4700,2650)","0","pure_quanta","I159";
;
PART_NUMBER"CH647KMEA04"
VALUE"47UF"
VOLTAGE"4V"
MATERIAL"X6S"
PACK_TYPE"C0805"
TOLERANCE"20%"
LOCATION"C1272"
CDS_LIB"pure_quanta"
$SEC"1"
CDS_SEC"1";
"B"
$PN"2"25;
"A"
$PN"1"22;
%"Q_CAP"
"1","(0,-725)","0","pure_quanta","I162";
;
PART_NUMBER"CH6471MEA02"
TOLERANCE"20%"
VOLTAGE"6.3V"
PACK_TYPE"C0805"
VALUE"47UF"
MATERIAL"X6S"
LOCATION"C1243"
CDS_LIB"pure_quanta"
$SEC"1"
CDS_SEC"1";
"B"
$PN"2"44;
"A"
$PN"1"20;
%"Q_CAP"
"1","(450,-725)","0","pure_quanta","I163";
;
PART_NUMBER"CH6471MEA02"
VOLTAGE"6.3V"
VALUE"47UF"
TOLERANCE"20%"
MATERIAL"X6S"
PACK_TYPE"C0805"
LOCATION"C1245"
CDS_LIB"pure_quanta"
$SEC"1"
CDS_SEC"1";
"B"
$PN"2"44;
"A"
$PN"1"20;
%"Q_INDUCTOR"
"1","(2700,3775)","0","pure_quanta","I164";
;
PART_NUMBER"CX5PX121001"
MATERIAL"EMPTY"
PACK_TYPE"SMLF"
VALUE"BLM15PX121SN1D/2A"
LOCATION"L2"
NEEDS_NO_SIZE"TRUE"
CDS_LIB"pure_quanta"
$SEC"1"
CDS_SEC"1";
"1"
$PN"1"2;
"2"
$PN"2"1;
%"Q_RES"
"1","(3150,4125)","0","pure_quanta","I165";
;
PART_NUMBER"CS00002JB13"
TOLERANCE"5%"
VALUE"0"
WATTAGE"1/16W"
PACK_TYPE"0402LF"
MATERIAL"CHIP"
$LOCATION"R4803"
CDS_LIB"pure_quanta"
CDS_LOCATION"R4803"
$SEC"1"
CDS_SEC"1";
"B"
$PN"2"1;
"A"
$PN"1"2;
%"UNIVERSAL_GND"
"1","(950,3475)","0","logical_power","I18";
;
ROOM"IO_SLOT"
HDL_POWER"GND"
CDS_LIB"logical_power";
"A"34;
%"UNIVERSAL_POWER"
"1","(50,4100)","0","logical_power","I20";
;
HDL_POWER"P1V05_PCH_AUX"
CDS_LIB"logical_power";
"A"18;
%"Q_CAP"
"1","(-1800,2500)","0","pure_quanta","I25";
;
PART_NUMBER"CH622KME901"
VOLTAGE"4V"
TOLERANCE"20%"
MATERIAL"X6S"
PACK_TYPE"C0603"
VALUE"22UF"
$LOCATION"C1186"
CDS_LIB"pure_quanta"
CDS_LOCATION"C1186"
$SEC"1"
CDS_SEC"1";
"B"
$PN"2"35;
"A"
$PN"1"13;
%"UNIVERSAL_POWER"
"1","(-2250,2775)","0","logical_power","I26";
;
HDL_POWER"P1V8_PCH_AUX"
CDS_LIB"logical_power";
"A"13;
%"Q_CAP"
"1","(-2250,2500)","0","pure_quanta","I27";
;
PART_NUMBER"CH622KME901"
TOLERANCE"20%"
VOLTAGE"4V"
PACK_TYPE"C0603"
VALUE"22UF"
MATERIAL"X6S"
$LOCATION"C1181"
CDS_LIB"pure_quanta"
CDS_LOCATION"C1181"
$SEC"1"
CDS_SEC"1";
"B"
$PN"2"35;
"A"
$PN"1"13;
%"UNIVERSAL_GND"
"1","(-900,2150)","0","logical_power","I28";
;
ROOM"IO_SLOT"
HDL_POWER"GND"
CDS_LIB"logical_power";
"A"35;
%"Q_CAP"
"1","(-900,2500)","0","pure_quanta","I29";
;
PART_NUMBER"CH622KME901"
VOLTAGE"4V"
VALUE"22UF"
TOLERANCE"20%"
MATERIAL"X6S"
PACK_TYPE"C0603"
$LOCATION"C1202"
CDS_LIB"pure_quanta"
CDS_LOCATION"C1202"
$SEC"1"
CDS_SEC"1";
"B"
$PN"2"35;
"A"
$PN"1"13;
%"Q_CAP"
"1","(-1350,2500)","0","pure_quanta","I30";
;
PART_NUMBER"CH622KME901"
MATERIAL"X6S"
TOLERANCE"20%"
VOLTAGE"4V"
VALUE"22UF"
PACK_TYPE"C0603"
$LOCATION"C1197"
CDS_LIB"pure_quanta"
CDS_LOCATION"C1197"
$SEC"1"
CDS_SEC"1";
"B"
$PN"2"35;
"A"
$PN"1"13;
%"UNIVERSAL_POWER"
"1","(-450,2775)","0","logical_power","I31";
;
HDL_POWER"P1V8_PCH_AUX"
CDS_LIB"logical_power";
"A"14;
%"Q_CAP"
"1","(-450,2500)","0","pure_quanta","I32";
;
PART_NUMBER"CH6101MEB01"
PACK_TYPE"C0402"
VALUE"10UF"
MATERIAL"X6S"
TOLERANCE"20%"
VOLTAGE"6.3V"
$LOCATION"C1207"
CDS_LIB"pure_quanta"
CDS_LOCATION"C1207"
$SEC"1"
CDS_SEC"1";
"B"
$PN"2"36;
"A"
$PN"1"14;
%"UNIVERSAL_GND"
"1","(-450,2150)","0","logical_power","I33";
;
ROOM"IO_SLOT"
HDL_POWER"GND"
CDS_LIB"logical_power";
"A"36;
%"UNIVERSAL_POWER"
"1","(-2250,4100)","0","logical_power","I4";
;
HDL_POWER"P1V05_PCH_AUX"
CDS_LIB"logical_power";
"A"15;
%"Q_CAP"
"1","(-1800,1200)","0","pure_quanta","I40";
;
PART_NUMBER"CH622KME901"
VOLTAGE"4V"
VALUE"22UF"
PACK_TYPE"C0603"
MATERIAL"X6S"
TOLERANCE"20%"
$LOCATION"C1187"
CDS_LIB"pure_quanta"
CDS_LOCATION"C1187"
$SEC"1"
CDS_SEC"1";
"B"
$PN"2"37;
"A"
$PN"1"16;
%"UNIVERSAL_POWER"
"1","(-2250,1475)","0","logical_power","I41";
;
HDL_POWER"P1V05_PCH_AUX"
CDS_LIB"logical_power";
"A"16;
%"Q_CAP"
"1","(-2250,1200)","0","pure_quanta","I42";
;
PART_NUMBER"CH622KME901"
VOLTAGE"4V"
TOLERANCE"20%"
VALUE"22UF"
MATERIAL"X6S"
PACK_TYPE"C0603"
$LOCATION"C1182"
CDS_LIB"pure_quanta"
CDS_LOCATION"C1182"
$SEC"1"
CDS_SEC"1";
"B"
$PN"2"37;
"A"
$PN"1"16;
%"Q_CAP"
"1","(-1350,1200)","0","pure_quanta","I43";
;
PART_NUMBER"CH622KME901"
VALUE"22UF"
MATERIAL"X6S"
TOLERANCE"20%"
PACK_TYPE"C0603"
VOLTAGE"4V"
$LOCATION"C1198"
CDS_LIB"pure_quanta"
CDS_LOCATION"C1198"
$SEC"1"
CDS_SEC"1";
"B"
$PN"2"37;
"A"
$PN"1"16;
%"UNIVERSAL_GND"
"1","(-1350,850)","0","logical_power","I44";
;
ROOM"IO_SLOT"
HDL_POWER"GND"
CDS_LIB"logical_power";
"A"37;
%"Q_CAP"
"1","(-450,1200)","0","pure_quanta","I45";
;
PART_NUMBER"CH6101MEB01"
MATERIAL"X6S"
TOLERANCE"20%"
VALUE"10UF"
VOLTAGE"6.3V"
PACK_TYPE"C0402"
$LOCATION"C1210"
CDS_LIB"pure_quanta"
CDS_LOCATION"C1210"
$SEC"1"
CDS_SEC"1";
"B"
$PN"2"39;
"A"
$PN"1"11;
%"Q_CAP"
"1","(-900,1200)","0","pure_quanta","I48";
;
PART_NUMBER"CH6101MEB01"
PACK_TYPE"C0402"
MATERIAL"X6S"
VOLTAGE"6.3V"
TOLERANCE"20%"
VALUE"10UF"
$LOCATION"C1203"
CDS_LIB"pure_quanta"
CDS_LOCATION"C1203"
$SEC"1"
CDS_SEC"1";
"B"
$PN"2"39;
"A"
$PN"1"11;
%"Q_CAP"
"1","(0,1200)","0","pure_quanta","I49";
;
PART_NUMBER"CH6101MEB01"
TOLERANCE"20%"
VALUE"10UF"
MATERIAL"X6S"
VOLTAGE"6.3V"
PACK_TYPE"C0402"
$LOCATION"C1231"
CDS_LIB"pure_quanta"
CDS_LOCATION"C1231"
$SEC"1"
CDS_SEC"1";
"B"
$PN"2"39;
"A"
$PN"1"11;
%"UNIVERSAL_GND"
"1","(-1350,3475)","0","logical_power","I5";
;
ROOM"IO_SLOT"
HDL_POWER"GND"
CDS_LIB"logical_power";
"A"38;
%"UNIVERSAL_GND"
"1","(0,850)","0","logical_power","I50";
;
ROOM"IO_SLOT"
HDL_POWER"GND"
CDS_LIB"logical_power";
"A"39;
%"Q_CAP"
"1","(-2250,475)","0","pure_quanta","I51";
;
PART_NUMBER"CH5222KEB01"
VOLTAGE"10V"
VALUE"2.2UF"
MATERIAL"X6S"
TOLERANCE"10%"
PACK_TYPE"C0402"
$LOCATION"C1183"
CDS_LIB"pure_quanta"
CDS_LOCATION"C1183"
$SEC"1"
CDS_SEC"1";
"B"
$PN"2"40;
"A"
$PN"1"12;
%"Q_CAP"
"1","(-1800,475)","0","pure_quanta","I58";
;
PART_NUMBER"CH5222KEB01"
MATERIAL"X6S"
TOLERANCE"10%"
VOLTAGE"10V"
PACK_TYPE"C0402"
VALUE"2.2UF"
$LOCATION"C1189"
CDS_LIB"pure_quanta"
CDS_LOCATION"C1189"
$SEC"1"
CDS_SEC"1";
"B"
$PN"2"40;
"A"
$PN"1"12;
%"Q_CAP"
"1","(-1350,475)","0","pure_quanta","I59";
;
PART_NUMBER"CH5222KEB01"
MATERIAL"X6S"
VALUE"2.2UF"
VOLTAGE"10V"
TOLERANCE"10%"
PACK_TYPE"C0402"
$LOCATION"C1200"
CDS_LIB"pure_quanta"
CDS_LOCATION"C1200"
$SEC"1"
CDS_SEC"1";
"B"
$PN"2"40;
"A"
$PN"1"12;
%"Q_CAP"
"1","(-2250,3825)","0","pure_quanta","I6";
;
PART_NUMBER"CH622KME901"
PACK_TYPE"C0603"
VALUE"22UF"
VOLTAGE"4V"
MATERIAL"X6S"
TOLERANCE"20%"
$LOCATION"C1178"
CDS_LIB"pure_quanta"
CDS_LOCATION"C1178"
$SEC"1"
CDS_SEC"1";
"B"
$PN"2"38;
"A"
$PN"1"15;
%"Q_CAP"
"1","(-900,475)","0","pure_quanta","I60";
;
PART_NUMBER"CH5222KEB01"
MATERIAL"X6S"
PACK_TYPE"C0402"
TOLERANCE"10%"
VOLTAGE"10V"
VALUE"2.2UF"
$LOCATION"C1204"
CDS_LIB"pure_quanta"
CDS_LOCATION"C1204"
$SEC"1"
CDS_SEC"1";
"B"
$PN"2"40;
"A"
$PN"1"12;
%"Q_CAP"
"1","(-450,475)","0","pure_quanta","I61";
;
PART_NUMBER"CH5222KEB01"
MATERIAL"X6S"
VALUE"2.2UF"
VOLTAGE"10V"
TOLERANCE"10%"
PACK_TYPE"C0402"
$LOCATION"C1214"
CDS_LIB"pure_quanta"
CDS_LOCATION"C1214"
$SEC"1"
CDS_SEC"1";
"B"
$PN"2"40;
"A"
$PN"1"12;
%"Q_CAP"
"1","(0,475)","0","pure_quanta","I63";
;
PART_NUMBER"CH5222KEB01"
MATERIAL"X6S"
VOLTAGE"10V"
PACK_TYPE"C0402"
VALUE"2.2UF"
TOLERANCE"10%"
$LOCATION"C1242"
CDS_LIB"pure_quanta"
CDS_LOCATION"C1242"
$SEC"1"
CDS_SEC"1";
"B"
$PN"2"40;
"A"
$PN"1"12;
%"UNIVERSAL_GND"
"1","(0,125)","0","logical_power","I64";
;
ROOM"IO_SLOT"
HDL_POWER"GND"
CDS_LIB"logical_power";
"A"40;
%"UNIVERSAL_GND"
"1","(950,825)","0","logical_power","I68";
;
ROOM"IO_SLOT"
HDL_POWER"GND"
CDS_LIB"logical_power";
"A"41;
%"Q_CAP"
"1","(-1800,3825)","0","pure_quanta","I7";
;
PART_NUMBER"CH622KME901"
PACK_TYPE"C0603"
VALUE"22UF"
MATERIAL"X6S"
TOLERANCE"20%"
VOLTAGE"4V"
$LOCATION"C1185"
CDS_LIB"pure_quanta"
CDS_LOCATION"C1185"
$SEC"1"
CDS_SEC"1";
"B"
$PN"2"38;
"A"
$PN"1"15;
%"Q_CAP"
"1","(-850,-725)","0","pure_quanta","I78";
;
PART_NUMBER"CH6101MEB01"
PACK_TYPE"C0402"
VOLTAGE"6.3V"
TOLERANCE"20%"
MATERIAL"X6S"
VALUE"10UF"
$LOCATION"C1206"
CDS_LIB"pure_quanta"
CDS_LOCATION"C1206"
$SEC"1"
CDS_SEC"1";
"B"
$PN"2"43;
"A"
$PN"1"4;
%"Q_CAP"
"1","(-1350,3825)","0","pure_quanta","I8";
;
PART_NUMBER"CH622KME901"
VOLTAGE"4V"
VALUE"22UF"
TOLERANCE"20%"
MATERIAL"X6S"
PACK_TYPE"C0603"
$LOCATION"C1192"
CDS_LIB"pure_quanta"
CDS_LOCATION"C1192"
$SEC"1"
CDS_SEC"1";
"B"
$PN"2"38;
"A"
$PN"1"15;
%"Q_CAP"
"1","(-1350,-725)","0","pure_quanta","I87";
;
PART_NUMBER"CH6221ME900"
MATERIAL"X6S"
VALUE"22UF"
VOLTAGE"6.3V"
PACK_TYPE"C0603"
TOLERANCE"20%"
$LOCATION"C1201"
CDS_LIB"pure_quanta"
CDS_LOCATION"C1201"
$SEC"1"
CDS_SEC"1";
"B"
$PN"2"42;
"A"
$PN"1"17;
%"UNIVERSAL_GND"
"1","(-1350,-1075)","0","logical_power","I88";
;
ROOM"IO_SLOT"
HDL_POWER"GND"
CDS_LIB"logical_power";
"A"42;
%"Q_CAP"
"1","(-1800,-725)","0","pure_quanta","I89";
;
PART_NUMBER"CH6221ME900"
PACK_TYPE"C0603"
TOLERANCE"20%"
VOLTAGE"6.3V"
VALUE"22UF"
MATERIAL"X6S"
$LOCATION"C1191"
CDS_LIB"pure_quanta"
CDS_LOCATION"C1191"
$SEC"1"
CDS_SEC"1";
"B"
$PN"2"42;
"A"
$PN"1"17;
%"UNIVERSAL_POWER"
"1","(-2250,-450)","0","logical_power","I90";
;
HDL_POWER"P3V3_AUX"
CDS_LIB"logical_power";
"A"17;
%"Q_CAP"
"1","(-2250,-725)","0","pure_quanta","I91";
;
PART_NUMBER"CH6221ME900"
VALUE"22UF"
VOLTAGE"6.3V"
TOLERANCE"20%"
PACK_TYPE"C0603"
MATERIAL"X6S"
$LOCATION"C1184"
CDS_LIB"pure_quanta"
CDS_LOCATION"C1184"
$SEC"1"
CDS_SEC"1";
"B"
$PN"2"42;
"A"
$PN"1"17;
%"UNIVERSAL_GND"
"1","(-850,-1075)","0","logical_power","I92";
;
ROOM"IO_SLOT"
HDL_POWER"GND"
CDS_LIB"logical_power";
"A"43;
%"UNIVERSAL_GND"
"1","(450,-1075)","0","logical_power","I93";
;
ROOM"IO_SLOT"
HDL_POWER"GND"
CDS_LIB"logical_power";
"A"44;
%"UNIVERSAL_POWER"
"1","(-850,-450)","0","logical_power","I94";
;
HDL_POWER"P3V3_AUX"
CDS_LIB"logical_power";
"A"4;
%"UNIVERSAL_POWER"
"1","(0,-450)","0","logical_power","I95";
;
HDL_POWER"P3V3_AUX"
CDS_LIB"logical_power";
"A"20;
%"UNIVERSAL_POWER"
"1","(4700,2925)","0","logical_power","I99";
;
HDL_POWER"P1V05_PCH_PLL_AUX"
CDS_LIB"logical_power";
"A"22;
END.
